(kicad_pcb
	(version 20241229)
	(generator "pcbnew")
	(generator_version "9.0")
	(general
		(thickness 1.62)
		(legacy_teardrops no)
	)
	(paper "A3")
	(title_block
		(title "COM Express 7 Baseboard")
		(date "2025-02-04")
		(rev "1.1.2")
		(company "Antmicro Ltd")
		(comment 1 "www.antmicro.com")
		(comment 9 "footprints 137-142 of 802")
	)
	(layers
		(0 "F.Cu" signal)
		(4 "In1.Cu" signal)
		(6 "In2.Cu" signal)
		(8 "In3.Cu" signal)
		(10 "In4.Cu" signal)
		(12 "In5.Cu" signal)
		(14 "In6.Cu" signal)
		(2 "B.Cu" signal)
		(9 "F.Adhes" user "F.Adhesive")
		(11 "B.Adhes" user "B.Adhesive")
		(13 "F.Paste" user)
		(15 "B.Paste" user)
		(5 "F.SilkS" user "F.Silkscreen")
		(7 "B.SilkS" user "B.Silkscreen")
		(1 "F.Mask" user)
		(3 "B.Mask" user)
		(17 "Dwgs.User" user "User.Drawings")
		(19 "Cmts.User" user "User.Comments")
		(21 "Eco1.User" user "User.Eco1")
		(23 "Eco2.User" user "User.Eco2")
		(25 "Edge.Cuts" user)
		(27 "Margin" user)
		(31 "F.CrtYd" user "F.Courtyard")
		(29 "B.CrtYd" user "B.Courtyard")
		(35 "F.Fab" user)
		(33 "B.Fab" user)
	)
	(footprint "antmicro-footprints:R_0402_1005Metric"
		(layer "F.Cu")
		(at 112.4 150.36 -90)
		(descr "Resistor SMD 0402")
		(tags "resistor SMD 0402")
		(property "Reference" "R211"
			(at -0.46 -4.5 90)
			(layer "F.SilkS")
			(effects
				(font
					(size 0.7 0.7)
					(thickness 0.15)
				)
				(justify right bottom)
			)
		)
		(property "Value" "R_1k_0402"
			(at -1.011843 1.772047 90)
			(layer "F.Fab")
			(effects
				(font
					(size 0.7 0.7)
					(thickness 0.15)
				)
				(justify right bottom)
			)
		)
		(property "Datasheet" "https://www.bourns.com/docs/product-datasheets/cr.pdf"
			(at 0 0 270)
			(layer "F.Fab")
			(hide yes)
			(effects
				(font
					(size 1.27 1.27)
					(thickness 0.15)
				)
			)
		)
		(property "Author" "Antmicro"
			(at -37.96 262.76 0)
			(layer "F.Fab")
			(hide yes)
			(effects
				(font
					(size 1 1)
					(thickness 0.15)
				)
			)
		)
		(property "License" "Apache-2.0"
			(at -37.96 262.76 0)
			(layer "F.Fab")
			(hide yes)
			(effects
				(font
					(size 1 1)
					(thickness 0.15)
				)
			)
		)
		(property "MPN" "CR0402-FX-1001GLF"
			(at -37.96 262.76 0)
			(layer "F.Fab")
			(hide yes)
			(effects
				(font
					(size 1 1)
					(thickness 0.15)
				)
			)
		)
		(property "Manufacturer" "Bourns"
			(at -37.96 262.76 0)
			(layer "F.Fab")
			(hide yes)
			(effects
				(font
					(size 1 1)
					(thickness 0.15)
				)
			)
		)
		(property "Public" "False"
			(at -37.96 262.76 0)
			(layer "F.Fab")
			(hide yes)
			(effects
				(font
					(size 1 1)
					(thickness 0.15)
				)
			)
		)
		(property "Tolerance" "1%"
			(at -37.96 262.76 0)
			(layer "F.Fab")
			(hide yes)
			(effects
				(font
					(size 1 1)
					(thickness 0.15)
				)
			)
		)
		(property "Val" "1k"
			(at -37.96 262.76 0)
			(layer "F.Fab")
			(hide yes)
			(effects
				(font
					(size 1 1)
					(thickness 0.15)
				)
			)
		)
		(sheetname "PCIe redriver")
		(sheetfile "pcie_redriver.kicad_sch")
		(attr smd dnp)
		(fp_rect
			(start -0.925 -0.47)
			(end 0.925 0.47)
			(stroke
				(width 0.05)
				(type default)
			)
			(fill no)
			(layer "F.CrtYd")
		)
		(fp_rect
			(start -0.5 -0.25)
			(end 0.5 0.25)
			(stroke
				(width 0.15)
				(type solid)
			)
			(fill no)
			(layer "F.Fab")
		)
		(pad "1" smd roundrect
			(at -0.48 0 270)
			(size 0.59 0.64)
			(layers "F.Cu" "F.Mask" "F.Paste")
			(roundrect_rratio 0.25)
			(net 1 "GND")
			(pintype "passive")
			(teardrops
				(best_length_ratio 0.2)
				(max_length 1)
				(best_width_ratio 0.9)
				(max_width 2)
				(curved_edges yes)
				(filter_ratio 0.9)
				(enabled yes)
				(allow_two_segments yes)
				(prefer_zone_connections yes)
			)
		)
		(pad "2" smd roundrect
			(at 0.48 0 270)
			(size 0.59 0.64)
			(layers "F.Cu" "F.Mask" "F.Paste")
			(roundrect_rratio 0.25)
			(net 627 "/PCIe redriver/TX_FG1")
			(pintype "passive")
			(teardrops
				(best_length_ratio 0.2)
				(max_length 1)
				(best_width_ratio 0.9)
				(max_width 2)
				(curved_edges yes)
				(filter_ratio 0.9)
				(enabled yes)
				(allow_two_segments yes)
				(prefer_zone_connections yes)
			)
		)
	)
	(footprint "antmicro-footprints:R_0201"
		(layer "F.Cu")
		(at 128.41 147.935 -90)
		(descr "Resistor SMD 0201")
		(tags "resistor SMD 0201")
		(property "Reference" "R312"
			(at 3.6 -0.29 90)
			(layer "F.SilkS")
			(effects
				(font
					(size 0.7 0.7)
					(thickness 0.15)
				)
				(justify right bottom)
			)
		)
		(property "Value" "R_0R_0201"
			(at 0 1.25 90)
			(layer "F.Fab")
			(effects
				(font
					(size 0.7 0.7)
					(thickness 0.15)
				)
				(justify right bottom)
			)
		)
		(property "Datasheet" "https://www.bourns.com/docs/product-datasheets/cr.pdf"
			(at 0 0 270)
			(layer "F.Fab")
			(hide yes)
			(effects
				(font
					(size 1.27 1.27)
					(thickness 0.15)
				)
			)
		)
		(property "Author" "Antmicro"
			(at -19.525 276.345 0)
			(layer "F.Fab")
			(hide yes)
			(effects
				(font
					(size 1 1)
					(thickness 0.15)
				)
			)
		)
		(property "License" "Apache-2.0"
			(at -19.525 276.345 0)
			(layer "F.Fab")
			(hide yes)
			(effects
				(font
					(size 1 1)
					(thickness 0.15)
				)
			)
		)
		(property "MPN" "CR0201-FX-0R00GLF"
			(at -19.525 276.345 0)
			(layer "F.Fab")
			(hide yes)
			(effects
				(font
					(size 1 1)
					(thickness 0.15)
				)
			)
		)
		(property "Manufacturer" "Bourns"
			(at -19.525 276.345 0)
			(layer "F.Fab")
			(hide yes)
			(effects
				(font
					(size 1 1)
					(thickness 0.15)
				)
			)
		)
		(property "Tolerance" "1%"
			(at -19.525 276.345 0)
			(layer "F.Fab")
			(hide yes)
			(effects
				(font
					(size 1 1)
					(thickness 0.15)
				)
			)
		)
		(property "Val" "0R"
			(at -19.525 276.345 0)
			(layer "F.Fab")
			(hide yes)
			(effects
				(font
					(size 1 1)
					(thickness 0.15)
				)
			)
		)
		(sheetname "KR to SFI #2")
		(sheetfile "kr_sfi.kicad_sch")
		(attr smd dnp)
		(fp_rect
			(start -0.7 -0.35)
			(end 0.7 0.35)
			(stroke
				(width 0.05)
				(type default)
			)
			(fill no)
			(layer "F.CrtYd")
		)
		(fp_rect
			(start -0.3 -0.15)
			(end 0.298 0.148)
			(stroke
				(width 0.15)
				(type solid)
			)
			(fill no)
			(layer "F.Fab")
		)
		(pad "" smd roundrect
			(at -0.346 0 270)
			(size 0.318 0.36)
			(layers "F.Paste")
			(roundrect_rratio 0.25)
			(teardrops
				(best_length_ratio 0.2)
				(max_length 1)
				(best_width_ratio 0.9)
				(max_width 2)
				(curved_edges yes)
				(filter_ratio 0.9)
				(enabled yes)
				(allow_two_segments yes)
				(prefer_zone_connections yes)
			)
		)
		(pad "" smd roundrect
			(at 0.344 0 270)
			(size 0.318 0.36)
			(layers "F.Paste")
			(roundrect_rratio 0.25)
			(teardrops
				(best_length_ratio 0.2)
				(max_length 1)
				(best_width_ratio 0.9)
				(max_width 2)
				(curved_edges yes)
				(filter_ratio 0.9)
				(enabled yes)
				(allow_two_segments yes)
				(prefer_zone_connections yes)
			)
		)
		(pad "1" smd roundrect
			(at -0.32 0 270)
			(size 0.46 0.4)
			(layers "F.Cu" "F.Mask")
			(roundrect_rratio 0.25)
			(net 880 "/2xSFP+/SFI1.TX-")
			(pintype "passive")
			(teardrops
				(best_length_ratio 0.2)
				(max_length 1)
				(best_width_ratio 0.9)
				(max_width 2)
				(curved_edges yes)
				(filter_ratio 0.9)
				(enabled yes)
				(allow_two_segments yes)
				(prefer_zone_connections yes)
			)
		)
		(pad "2" smd roundrect
			(at 0.32 0 270)
			(size 0.46 0.4)
			(layers "F.Cu" "F.Mask")
			(roundrect_rratio 0.25)
			(net 951 "/2xSFP+/KR to SFI #2/BYP_TX-")
			(pintype "passive")
			(teardrops
				(best_length_ratio 0.2)
				(max_length 1)
				(best_width_ratio 0.9)
				(max_width 2)
				(curved_edges yes)
				(filter_ratio 0.9)
				(enabled yes)
				(allow_two_segments yes)
				(prefer_zone_connections yes)
			)
		)
	)
	(footprint "antmicro-footprints:TP_SMD_0.75mm"
		(layer "F.Cu")
		(at 133.64 128.71)
		(property "Reference" "TP80"
			(at 0.51 -3.3 90)
			(layer "F.SilkS")
			(effects
				(font
					(size 0.7 0.7)
					(thickness 0.15)
				)
				(justify left bottom)
			)
		)
		(property "Value" "TP_0.75mm_SMD"
			(at 0 1.2 0)
			(layer "F.Fab")
			(effects
				(font
					(size 0.7 0.7)
					(thickness 0.15)
				)
				(justify left bottom)
			)
		)
		(property "Author" "Antmicro"
			(at 0 0 0)
			(layer "F.Fab")
			(hide yes)
			(effects
				(font
					(size 1 1)
					(thickness 0.15)
				)
			)
		)
		(property "License" "Apache-2.0"
			(at 0 0 0)
			(layer "F.Fab")
			(hide yes)
			(effects
				(font
					(size 1 1)
					(thickness 0.15)
				)
			)
		)
		(property "MPN" ""
			(at 0 0 0)
			(layer "F.Fab")
			(hide yes)
			(effects
				(font
					(size 1 1)
					(thickness 0.15)
				)
			)
		)
		(property "Manufacturer" ""
			(at 0 0 0)
			(layer "F.Fab")
			(hide yes)
			(effects
				(font
					(size 1 1)
					(thickness 0.15)
				)
			)
		)
		(property "Public" "False"
			(at 0 0 0)
			(layer "F.Fab")
			(hide yes)
			(effects
				(font
					(size 1 1)
					(thickness 0.15)
				)
			)
		)
		(sheetname "KR to SFI #2")
		(sheetfile "kr_sfi.kicad_sch")
		(attr exclude_from_pos_files exclude_from_bom)
		(fp_circle
			(center 0 0)
			(end 0.475 0)
			(stroke
				(width 0.05)
				(type default)
			)
			(fill no)
			(layer "F.CrtYd")
		)
		(pad "1" smd circle
			(at 0 0)
			(size 0.75 0.75)
			(layers "F.Cu" "F.Mask")
			(net 743 "/2xSFP+/KR to SFI #2/TDO")
			(pinfunction "1")
			(pintype "passive")
			(teardrops
				(best_length_ratio 0.4)
				(max_length 1)
				(best_width_ratio 0.9)
				(max_width 2)
				(curved_edges yes)
				(filter_ratio 0.9)
				(enabled yes)
				(allow_two_segments yes)
				(prefer_zone_connections yes)
			)
		)
	)
	(footprint "antmicro-footprints:C_0402_1005Metric"
		(layer "F.Cu")
		(at 241.75 128.31 -90)
		(descr "Capacitor SMD 0402")
		(tags "capacitor SMD 0402")
		(property "Reference" "C207"
			(at -1.5 0.5 90)
			(layer "F.SilkS")
			(effects
				(font
					(size 0.7 0.7)
					(thickness 0.15)
				)
				(justify right bottom)
			)
		)
		(property "Value" "C_100n_0402"
			(at -1.022927 2.155213 90)
			(layer "F.Fab")
			(effects
				(font
					(size 0.7 0.7)
					(thickness 0.15)
				)
				(justify right bottom)
			)
		)
		(property "Datasheet" "https://www.murata.com/products/productdetail?partno=GRM155R61H104KE14%23"
			(at 0 0 270)
			(layer "F.Fab")
			(hide yes)
			(effects
				(font
					(size 1.27 1.27)
					(thickness 0.15)
				)
			)
		)
		(property "Author" "Antmicro"
			(at 113.44 370.06 0)
			(layer "F.Fab")
			(hide yes)
			(effects
				(font
					(size 1 1)
					(thickness 0.15)
				)
			)
		)
		(property "Dielectric" "X5R"
			(at 113.44 370.06 0)
			(layer "F.Fab")
			(hide yes)
			(effects
				(font
					(size 1 1)
					(thickness 0.15)
				)
			)
		)
		(property "License" "Apache-2.0"
			(at 113.44 370.06 0)
			(layer "F.Fab")
			(hide yes)
			(effects
				(font
					(size 1 1)
					(thickness 0.15)
				)
			)
		)
		(property "MPN" "GRM155R61H104KE14D"
			(at 113.44 370.06 0)
			(layer "F.Fab")
			(hide yes)
			(effects
				(font
					(size 1 1)
					(thickness 0.15)
				)
			)
		)
		(property "Manufacturer" "Murata"
			(at 113.44 370.06 0)
			(layer "F.Fab")
			(hide yes)
			(effects
				(font
					(size 1 1)
					(thickness 0.15)
				)
			)
		)
		(property "Public" "False"
			(at 113.44 370.06 0)
			(layer "F.Fab")
			(hide yes)
			(effects
				(font
					(size 1 1)
					(thickness 0.15)
				)
			)
		)
		(property "Val" "100n"
			(at 113.44 370.06 0)
			(layer "F.Fab")
			(hide yes)
			(effects
				(font
					(size 1 1)
					(thickness 0.15)
				)
			)
		)
		(property "Voltage" "50V"
			(at 113.44 370.06 0)
			(layer "F.Fab")
			(hide yes)
			(effects
				(font
					(size 1 1)
					(thickness 0.15)
				)
			)
		)
		(sheetname "Com Express 7 MGMT")
		(sheetfile "com_express_7_mgmt.kicad_sch")
		(attr smd dnp)
		(fp_rect
			(start -0.925 -0.47)
			(end 0.925 0.47)
			(stroke
				(width 0.05)
				(type default)
			)
			(fill no)
			(layer "F.CrtYd")
		)
		(fp_line
			(start -0.494 0.248)
			(end -0.494 -0.25)
			(stroke
				(width 0.15)
				(type solid)
			)
			(layer "F.Fab")
		)
		(fp_line
			(start 0.504 0.248)
			(end -0.494 0.248)
			(stroke
				(width 0.15)
				(type solid)
			)
			(layer "F.Fab")
		)
		(fp_line
			(start -0.494 -0.25)
			(end 0.504 -0.25)
			(stroke
				(width 0.15)
				(type solid)
			)
			(layer "F.Fab")
		)
		(fp_line
			(start 0.504 -0.25)
			(end 0.504 0.248)
			(stroke
				(width 0.15)
				(type solid)
			)
			(layer "F.Fab")
		)
		(pad "1" smd roundrect
			(at -0.48 0 270)
			(size 0.59 0.64)
			(layers "F.Cu" "F.Mask" "F.Paste")
			(roundrect_rratio 0.25)
			(net 1 "GND")
			(pintype "passive")
			(teardrops
				(best_length_ratio 0.2)
				(max_length 1)
				(best_width_ratio 0.9)
				(max_width 2)
				(curved_edges yes)
				(filter_ratio 0.9)
				(enabled yes)
				(allow_two_segments yes)
				(prefer_zone_connections yes)
			)
		)
		(pad "2" smd roundrect
			(at 0.48 0 270)
			(size 0.59 0.64)
			(layers "F.Cu" "F.Mask" "F.Paste")
			(roundrect_rratio 0.25)
			(net 48 "Net-(U34-ONT)")
			(pintype "passive")
			(teardrops
				(best_length_ratio 0.2)
				(max_length 1)
				(best_width_ratio 0.9)
				(max_width 2)
				(curved_edges yes)
				(filter_ratio 0.9)
				(enabled yes)
				(allow_two_segments yes)
				(prefer_zone_connections yes)
			)
		)
	)
	(footprint "antmicro-footprints:R_0402_1005Metric"
		(layer "F.Cu")
		(at 211.28 127.09 180)
		(descr "Resistor SMD 0402")
		(tags "resistor SMD 0402")
		(property "Reference" "R182"
			(at 0.83 -0.12 0)
			(layer "F.SilkS")
			(effects
				(font
					(size 0.7 0.7)
					(thickness 0.15)
				)
				(justify right bottom)
			)
		)
		(property "Value" "R_1k_0402"
			(at -1.011843 1.772047 0)
			(layer "F.Fab")
			(effects
				(font
					(size 0.7 0.7)
					(thickness 0.15)
				)
				(justify right bottom)
			)
		)
		(property "Datasheet" "https://www.bourns.com/docs/product-datasheets/cr.pdf"
			(at 0 0 180)
			(layer "F.Fab")
			(hide yes)
			(effects
				(font
					(size 1.27 1.27)
					(thickness 0.15)
				)
			)
		)
		(property "Author" "Antmicro"
			(at 422.56 254.18 0)
			(layer "F.Fab")
			(hide yes)
			(effects
				(font
					(size 1 1)
					(thickness 0.15)
				)
			)
		)
		(property "License" "Apache-2.0"
			(at 422.56 254.18 0)
			(layer "F.Fab")
			(hide yes)
			(effects
				(font
					(size 1 1)
					(thickness 0.15)
				)
			)
		)
		(property "MPN" "CR0402-FX-1001GLF"
			(at 422.56 254.18 0)
			(layer "F.Fab")
			(hide yes)
			(effects
				(font
					(size 1 1)
					(thickness 0.15)
				)
			)
		)
		(property "Manufacturer" "Bourns"
			(at 422.56 254.18 0)
			(layer "F.Fab")
			(hide yes)
			(effects
				(font
					(size 1 1)
					(thickness 0.15)
				)
			)
		)
		(property "Public" "False"
			(at 422.56 254.18 0)
			(layer "F.Fab")
			(hide yes)
			(effects
				(font
					(size 1 1)
					(thickness 0.15)
				)
			)
		)
		(property "Tolerance" "1%"
			(at 422.56 254.18 0)
			(layer "F.Fab")
			(hide yes)
			(effects
				(font
					(size 1 1)
					(thickness 0.15)
				)
			)
		)
		(property "Val" "1k"
			(at 422.56 254.18 0)
			(layer "F.Fab")
			(hide yes)
			(effects
				(font
					(size 1 1)
					(thickness 0.15)
				)
			)
		)
		(sheetname "PCIe misc")
		(sheetfile "pcie_misc.kicad_sch")
		(attr smd)
		(fp_rect
			(start -0.925 -0.47)
			(end 0.925 0.47)
			(stroke
				(width 0.05)
				(type default)
			)
			(fill no)
			(layer "F.CrtYd")
		)
		(fp_rect
			(start -0.5 -0.25)
			(end 0.5 0.25)
			(stroke
				(width 0.15)
				(type solid)
			)
			(fill no)
			(layer "F.Fab")
		)
		(pad "1" smd roundrect
			(at -0.48 0 180)
			(size 0.59 0.64)
			(layers "F.Cu" "F.Mask" "F.Paste")
			(roundrect_rratio 0.25)
			(net 602 "Net-(U37-~{OE0})")
			(pintype "passive")
			(teardrops
				(best_length_ratio 0.2)
				(max_length 1)
				(best_width_ratio 0.9)
				(max_width 2)
				(curved_edges yes)
				(filter_ratio 0.9)
				(enabled yes)
				(allow_two_segments yes)
				(prefer_zone_connections yes)
			)
		)
		(pad "2" smd roundrect
			(at 0.48 0 180)
			(size 0.59 0.64)
			(layers "F.Cu" "F.Mask" "F.Paste")
			(roundrect_rratio 0.25)
			(net 1 "GND")
			(pintype "passive")
			(teardrops
				(best_length_ratio 0.2)
				(max_length 1)
				(best_width_ratio 0.9)
				(max_width 2)
				(curved_edges yes)
				(filter_ratio 0.9)
				(enabled yes)
				(allow_two_segments yes)
				(prefer_zone_connections yes)
			)
		)
	)
	(footprint "antmicro-footprints:C_0402_1005Metric"
		(layer "F.Cu")
		(at 300.55 95.31 -90)
		(descr "Capacitor SMD 0402")
		(tags "capacitor SMD 0402")
		(property "Reference" "C67"
			(at -1.15 0.5 90)
			(layer "F.SilkS")
			(effects
				(font
					(size 0.7 0.7)
					(thickness 0.15)
				)
				(justify right bottom)
			)
		)
		(property "Value" "C_1u_0402"
			(at -1.022927 2.155213 90)
			(layer "F.Fab")
			(effects
				(font
					(size 0.7 0.7)
					(thickness 0.15)
				)
				(justify right bottom)
			)
		)
		(property "Datasheet" "https://product.tdk.com/en/search/capacitor/ceramic/mlcc/info?part_no=C1005X6S1A105K050BC"
			(at 0 0 270)
			(layer "F.Fab")
			(hide yes)
			(effects
				(font
					(size 1.27 1.27)
					(thickness 0.15)
				)
			)
		)
		(property "Author" "Antmicro"
			(at 205.24 395.86 0)
			(layer "F.Fab")
			(hide yes)
			(effects
				(font
					(size 1 1)
					(thickness 0.15)
				)
			)
		)
		(property "Dielectric" ""
			(at 205.24 395.86 0)
			(layer "F.Fab")
			(hide yes)
			(effects
				(font
					(size 1 1)
					(thickness 0.15)
				)
			)
		)
		(property "License" "Apache-2.0"
			(at 205.24 395.86 0)
			(layer "F.Fab")
			(hide yes)
			(effects
				(font
					(size 1 1)
					(thickness 0.15)
				)
			)
		)
		(property "MPN" "C1005X6S1A105K050BC"
			(at 205.24 395.86 0)
			(layer "F.Fab")
			(hide yes)
			(effects
				(font
					(size 1 1)
					(thickness 0.15)
				)
			)
		)
		(property "Manufacturer" "TDK"
			(at 205.24 395.86 0)
			(layer "F.Fab")
			(hide yes)
			(effects
				(font
					(size 1 1)
					(thickness 0.15)
				)
			)
		)
		(property "Public" "False"
			(at 205.24 395.86 0)
			(layer "F.Fab")
			(hide yes)
			(effects
				(font
					(size 1 1)
					(thickness 0.15)
				)
			)
		)
		(property "Val" "1u"
			(at 205.24 395.86 0)
			(layer "F.Fab")
			(hide yes)
			(effects
				(font
					(size 1 1)
					(thickness 0.15)
				)
			)
		)
		(property "Voltage" ""
			(at 205.24 395.86 0)
			(layer "F.Fab")
			(hide yes)
			(effects
				(font
					(size 1 1)
					(thickness 0.15)
				)
			)
		)
		(sheetname "Power")
		(sheetfile "power.kicad_sch")
		(attr smd)
		(fp_rect
			(start -0.925 -0.47)
			(end 0.925 0.47)
			(stroke
				(width 0.05)
				(type default)
			)
			(fill no)
			(layer "F.CrtYd")
		)
		(fp_line
			(start -0.494 0.248)
			(end -0.494 -0.25)
			(stroke
				(width 0.15)
				(type solid)
			)
			(layer "F.Fab")
		)
		(fp_line
			(start 0.504 0.248)
			(end -0.494 0.248)
			(stroke
				(width 0.15)
				(type solid)
			)
			(layer "F.Fab")
		)
		(fp_line
			(start -0.494 -0.25)
			(end 0.504 -0.25)
			(stroke
				(width 0.15)
				(type solid)
			)
			(layer "F.Fab")
		)
		(fp_line
			(start 0.504 -0.25)
			(end 0.504 0.248)
			(stroke
				(width 0.15)
				(type solid)
			)
			(layer "F.Fab")
		)
		(pad "1" smd roundrect
			(at -0.48 0 270)
			(size 0.59 0.64)
			(layers "F.Cu" "F.Mask" "F.Paste")
			(roundrect_rratio 0.25)
			(net 1 "GND")
			(pintype "passive")
			(teardrops
				(best_length_ratio 0.2)
				(max_length 1)
				(best_width_ratio 0.9)
				(max_width 2)
				(curved_edges yes)
				(filter_ratio 0.9)
				(enabled yes)
				(allow_two_segments yes)
				(prefer_zone_connections yes)
			)
		)
		(pad "2" smd roundrect
			(at 0.48 0 270)
			(size 0.59 0.64)
			(layers "F.Cu" "F.Mask" "F.Paste")
			(roundrect_rratio 0.25)
			(net 77 "+5V_AON")
			(pintype "passive")
			(teardrops
				(best_length_ratio 0.2)
				(max_length 1)
				(best_width_ratio 0.9)
				(max_width 2)
				(curved_edges yes)
				(filter_ratio 0.9)
				(enabled yes)
				(allow_two_segments yes)
				(prefer_zone_connections yes)
			)
		)
	)
)
